# S9S_MB_2U (Grand Teton) — schematic netlist excerpt (pin names and nets, part order shuffled) for the footprints in the layout excerpt that follows; sources: Cadence DE-HDL packaged netlist, KiCad conversion of 03242023_DA0F0TMBIJ0_F0T_Motherboard_J_brd_V01_OCP.brd

C13  Q_CAP  10UF 16V 10% X6S  pkg C0805  page 85 : A = P12V_S3_AUX_CPU0_NVDIMM ; B = GND
C2324  Q_CAP  0.1UF 25V 10% EMPTY  pkg 0402  page 196 : A = P3V3_AUX ; B = GND
R839  Q_RES  1K 1% CHIP  pkg 0402LF  page 129 : A = PVCCD_HV_CPU0 ; B = RST_M_GH_CPU0_FPGA_N

(kicad_pcb
	(version 20260206)
	(generator "pcbnew")
	(generator_version "10.0")
	(general
		(thickness 1.6)
		(legacy_teardrops no)
	)
	(paper "A4")
	(title_block
		(title "03242023_DA0F0TMBIJ0_F0T_Motherboard_J_brd_V01_OCP.brd")
		(comment 1 "Grand Teton / footprints 4645-4647 of 6105")
	)
	(layers
		(0 "F.Cu" signal "TOP")
		(4 "In1.Cu" signal "GND")
		(6 "In2.Cu" signal "IN1")
		(8 "In3.Cu" signal "GND1")
		(10 "In4.Cu" signal "IN2")
		(12 "In5.Cu" signal "GND2")
		(14 "In6.Cu" signal "IN3")
		(16 "In7.Cu" signal "GND3")
		(18 "In8.Cu" signal "VCC")
		(20 "In9.Cu" signal "VCC1")
		(22 "In10.Cu" signal "GND4")
		(24 "In11.Cu" signal "IN4")
		(26 "In12.Cu" signal "GND5")
		(28 "In13.Cu" signal "IN5")
		(30 "In14.Cu" signal "GND6")
		(32 "In15.Cu" signal "IN6")
		(34 "In16.Cu" signal "GND7")
		(2 "B.Cu" signal "BOTTOM")
		(9 "F.Adhes" user "F.Adhesive")
		(11 "B.Adhes" user "B.Adhesive")
		(13 "F.Paste" user "Package Geometry/Pastemask Top")
		(15 "B.Paste" user "Package Geometry/Pastemask Bottom")
		(5 "F.SilkS" user "Ref Des/Silkscreen Top")
		(7 "B.SilkS" user "Ref Des/Silkscreen Bottom")
		(1 "F.Mask" user "Board Geometry/Soldermask Top")
		(3 "B.Mask" user "Board Geometry/Soldermask Bottom")
		(17 "Dwgs.User" user "User.Drawings")
		(19 "Cmts.User" user "User.Comments")
		(21 "Eco1.User" user "User.Eco1")
		(23 "Eco2.User" user "User.Eco2")
		(25 "Edge.Cuts" user "Board Geometry/Outline")
		(27 "Margin" user)
		(31 "F.CrtYd" user "Package Geometry/Place Bound Top")
		(29 "B.CrtYd" user "Package Geometry/Place Bound Bottom")
		(35 "F.Fab" user "Ref Des/Assembly Top")
		(33 "B.Fab" user "Ref Des/Assembly Bottom")
	)
	(footprint ""
		(layer "B.Cu")
		(at 137.80262 -30.157928 -90)
		(property "Reference" "C2324"
			(at 0 0 90)
			(layer "B.SilkS")
			(hide yes)
			(effects
				(font
					(size 1.27 1.27)
				)
				(justify mirror)
			)
		)
		(property "Value" ""
			(at 0 0 90)
			(layer "B.Fab")
			(effects
				(font
					(size 1.27 1.27)
				)
				(justify mirror)
			)
		)
		(duplicate_pad_numbers_are_jumpers no)
		(fp_line
			(start -0.7874 0.4064)
			(end 0.7874 0.4064)
			(stroke
				(width 0.1524)
				(type default)
			)
			(layer "B.SilkS")
		)
		(fp_line
			(start 0.7874 0.4064)
			(end 0.7874 -0.4064)
			(stroke
				(width 0.1524)
				(type default)
			)
			(layer "B.SilkS")
		)
		(fp_line
			(start -0.7874 -0.4064)
			(end -0.7874 0.4064)
			(stroke
				(width 0.1524)
				(type default)
			)
			(layer "B.SilkS")
		)
		(fp_line
			(start 0.7874 -0.4064)
			(end -0.7874 -0.4064)
			(stroke
				(width 0.1524)
				(type default)
			)
			(layer "B.SilkS")
		)
		(fp_line
			(start -0.67945 0.3048)
			(end -0.120396 0.3048)
			(stroke
				(width 0.1)
				(type default)
			)
			(layer "B.Fab")
		)
		(fp_line
			(start -0.120396 0.3048)
			(end -0.120396 0.2794)
			(stroke
				(width 0.1)
				(type default)
			)
			(layer "B.Fab")
		)
		(fp_line
			(start 0.12065 0.3048)
			(end 0.67945 0.3048)
			(stroke
				(width 0.1)
				(type default)
			)
			(layer "B.Fab")
		)
		(fp_line
			(start 0.67945 0.3048)
			(end 0.67945 -0.305054)
			(stroke
				(width 0.1)
				(type default)
			)
			(layer "B.Fab")
		)
		(fp_line
			(start -0.120396 0.2794)
			(end 0.12065 0.2794)
			(stroke
				(width 0.1)
				(type default)
			)
			(layer "B.Fab")
		)
		(fp_line
			(start 0.12065 0.2794)
			(end 0.12065 0.3048)
			(stroke
				(width 0.1)
				(type default)
			)
			(layer "B.Fab")
		)
		(fp_line
			(start -0.12065 -0.2794)
			(end -0.12065 -0.3048)
			(stroke
				(width 0.1)
				(type default)
			)
			(layer "B.Fab")
		)
		(fp_line
			(start 0.12065 -0.2794)
			(end -0.12065 -0.2794)
			(stroke
				(width 0.1)
				(type default)
			)
			(layer "B.Fab")
		)
		(fp_line
			(start -0.67945 -0.3048)
			(end -0.67945 0.3048)
			(stroke
				(width 0.1)
				(type default)
			)
			(layer "B.Fab")
		)
		(fp_line
			(start -0.12065 -0.3048)
			(end -0.67945 -0.3048)
			(stroke
				(width 0.1)
				(type default)
			)
			(layer "B.Fab")
		)
		(fp_line
			(start 0.12065 -0.305054)
			(end 0.12065 -0.2794)
			(stroke
				(width 0.1)
				(type default)
			)
			(layer "B.Fab")
		)
		(fp_line
			(start 0.67945 -0.305054)
			(end 0.12065 -0.305054)
			(stroke
				(width 0.1)
				(type default)
			)
			(layer "B.Fab")
		)
		(pad "1" smd circle
			(at 0.40005 0 90)
			(size 0 0)
			(layers "B.Cu" "B.Mask" "B.Paste")
			(net "P3V3_AUX")
		)
		(pad "2" smd circle
			(at -0.40005 0 90)
			(size 0 0)
			(layers "B.Cu" "B.Mask" "B.Paste")
			(net "GND")
		)
	)
	(footprint ""
		(layer "B.Cu")
		(at 435.59857 -193.567304 -90)
		(property "Reference" "R839"
			(at 0 0 90)
			(layer "B.SilkS")
			(hide yes)
			(effects
				(font
					(size 1.27 1.27)
				)
				(justify mirror)
			)
		)
		(property "Value" ""
			(at 0 0 90)
			(layer "B.Fab")
			(effects
				(font
					(size 1.27 1.27)
				)
				(justify mirror)
			)
		)
		(duplicate_pad_numbers_are_jumpers no)
		(fp_line
			(start -0.7874 0.4064)
			(end 0.7874 0.4064)
			(stroke
				(width 0.1524)
				(type default)
			)
			(layer "B.SilkS")
		)
		(fp_line
			(start 0.7874 0.4064)
			(end 0.7874 -0.4064)
			(stroke
				(width 0.1524)
				(type default)
			)
			(layer "B.SilkS")
		)
		(fp_line
			(start -0.7874 -0.4064)
			(end -0.7874 0.4064)
			(stroke
				(width 0.1524)
				(type default)
			)
			(layer "B.SilkS")
		)
		(fp_line
			(start 0.7874 -0.4064)
			(end -0.7874 -0.4064)
			(stroke
				(width 0.1524)
				(type default)
			)
			(layer "B.SilkS")
		)
		(fp_line
			(start -0.67945 0.3048)
			(end -0.120396 0.3048)
			(stroke
				(width 0.1)
				(type default)
			)
			(layer "B.Fab")
		)
		(fp_line
			(start -0.120396 0.3048)
			(end -0.120396 0.2794)
			(stroke
				(width 0.1)
				(type default)
			)
			(layer "B.Fab")
		)
		(fp_line
			(start 0.12065 0.3048)
			(end 0.67945 0.3048)
			(stroke
				(width 0.1)
				(type default)
			)
			(layer "B.Fab")
		)
		(fp_line
			(start 0.67945 0.3048)
			(end 0.67945 -0.305054)
			(stroke
				(width 0.1)
				(type default)
			)
			(layer "B.Fab")
		)
		(fp_line
			(start -0.120396 0.2794)
			(end 0.12065 0.2794)
			(stroke
				(width 0.1)
				(type default)
			)
			(layer "B.Fab")
		)
		(fp_line
			(start 0.12065 0.2794)
			(end 0.12065 0.3048)
			(stroke
				(width 0.1)
				(type default)
			)
			(layer "B.Fab")
		)
		(fp_line
			(start -0.12065 -0.2794)
			(end -0.12065 -0.3048)
			(stroke
				(width 0.1)
				(type default)
			)
			(layer "B.Fab")
		)
		(fp_line
			(start 0.12065 -0.2794)
			(end -0.12065 -0.2794)
			(stroke
				(width 0.1)
				(type default)
			)
			(layer "B.Fab")
		)
		(fp_line
			(start -0.67945 -0.3048)
			(end -0.67945 0.3048)
			(stroke
				(width 0.1)
				(type default)
			)
			(layer "B.Fab")
		)
		(fp_line
			(start -0.12065 -0.3048)
			(end -0.67945 -0.3048)
			(stroke
				(width 0.1)
				(type default)
			)
			(layer "B.Fab")
		)
		(fp_line
			(start 0.12065 -0.305054)
			(end 0.12065 -0.2794)
			(stroke
				(width 0.1)
				(type default)
			)
			(layer "B.Fab")
		)
		(fp_line
			(start 0.67945 -0.305054)
			(end 0.12065 -0.305054)
			(stroke
				(width 0.1)
				(type default)
			)
			(layer "B.Fab")
		)
		(pad "1" smd circle
			(at 0.40005 0 90)
			(size 0 0)
			(layers "B.Cu" "B.Mask" "B.Paste")
			(net "PVCCD_HV_CPU0")
		)
		(pad "2" smd circle
			(at -0.40005 0 90)
			(size 0 0)
			(layers "B.Cu" "B.Mask" "B.Paste")
			(net "RST_M_GH_CPU0_FPGA_N")
		)
	)
	(footprint ""
		(layer "B.Cu")
		(at 297.876214 -321.549776 -90)
		(property "Reference" "C13"
			(at 0 0 90)
			(layer "B.SilkS")
			(hide yes)
			(effects
				(font
					(size 1.27 1.27)
				)
				(justify mirror)
			)
		)
		(property "Value" ""
			(at 0 0 90)
			(layer "B.Fab")
			(effects
				(font
					(size 1.27 1.27)
				)
				(justify mirror)
			)
		)
		(duplicate_pad_numbers_are_jumpers no)
		(fp_line
			(start -1.524 0.762)
			(end 1.524 0.762)
			(stroke
				(width 0.1524)
				(type default)
			)
			(layer "B.SilkS")
		)
		(fp_line
			(start 1.524 0.762)
			(end 1.524 -0.762)
			(stroke
				(width 0.1524)
				(type default)
			)
			(layer "B.SilkS")
		)
		(fp_line
			(start -1.524 -0.762)
			(end -1.524 0.762)
			(stroke
				(width 0.1524)
				(type default)
			)
			(layer "B.SilkS")
		)
		(fp_line
			(start 1.524 -0.762)
			(end -1.524 -0.762)
			(stroke
				(width 0.1524)
				(type default)
			)
			(layer "B.SilkS")
		)
		(fp_line
			(start -1.1049 0.724916)
			(end -1.1049 -0.724916)
			(stroke
				(width 0.1)
				(type default)
			)
			(layer "B.Fab")
		)
		(fp_line
			(start 1.1049 0.724916)
			(end -1.1049 0.724916)
			(stroke
				(width 0.1)
				(type default)
			)
			(layer "B.Fab")
		)
		(fp_line
			(start -1.1049 -0.724916)
			(end 1.1049 -0.724916)
			(stroke
				(width 0.1)
				(type default)
			)
			(layer "B.Fab")
		)
		(fp_line
			(start 1.1049 -0.724916)
			(end 1.1049 0.724916)
			(stroke
				(width 0.1)
				(type default)
			)
			(layer "B.Fab")
		)
		(pad "1" smd rect
			(at 0.889 0 270)
			(size 1.016 1.27)
			(layers "B.Cu" "B.Mask" "B.Paste")
			(net "P12V_S3_AUX_CPU0_NVDIMM")
		)
		(pad "2" smd rect
			(at -0.889 0 270)
			(size 1.016 1.27)
			(layers "B.Cu" "B.Mask" "B.Paste")
			(net "GND")
		)
	)
)
